# S9S_MB_2U (Grand Teton) — schematic netlist excerpt (pin names and nets, part order shuffled) for the footprints in the layout excerpt that follows; sources: Cadence DE-HDL packaged netlist, KiCad conversion of 03242023_DA0F0TMBIJ0_F0T_Motherboard_J_brd_V01_OCP.brd

C310  Q_CAP  22UF 4V 20% X6S  pkg C0402  page 77 : A = PVNN_MAIN_CPU1 ; B = GND

(kicad_pcb
	(version 20260206)
	(generator "pcbnew")
	(generator_version "10.0")
	(general
		(thickness 1.6)
		(legacy_teardrops no)
	)
	(paper "A4")
	(title_block
		(title "03242023_DA0F0TMBIJ0_F0T_Motherboard_J_brd_V01_OCP.brd")
		(comment 1 "Grand Teton / footprints 3427-3427 of 6105")
	)
	(layers
		(0 "F.Cu" signal "TOP")
		(4 "In1.Cu" signal "GND")
		(6 "In2.Cu" signal "IN1")
		(8 "In3.Cu" signal "GND1")
		(10 "In4.Cu" signal "IN2")
		(12 "In5.Cu" signal "GND2")
		(14 "In6.Cu" signal "IN3")
		(16 "In7.Cu" signal "GND3")
		(18 "In8.Cu" signal "VCC")
		(20 "In9.Cu" signal "VCC1")
		(22 "In10.Cu" signal "GND4")
		(24 "In11.Cu" signal "IN4")
		(26 "In12.Cu" signal "GND5")
		(28 "In13.Cu" signal "IN5")
		(30 "In14.Cu" signal "GND6")
		(32 "In15.Cu" signal "IN6")
		(34 "In16.Cu" signal "GND7")
		(2 "B.Cu" signal "BOTTOM")
		(9 "F.Adhes" user "F.Adhesive")
		(11 "B.Adhes" user "B.Adhesive")
		(13 "F.Paste" user "Package Geometry/Pastemask Top")
		(15 "B.Paste" user "Package Geometry/Pastemask Bottom")
		(5 "F.SilkS" user "Ref Des/Silkscreen Top")
		(7 "B.SilkS" user "Ref Des/Silkscreen Bottom")
		(1 "F.Mask" user "Board Geometry/Soldermask Top")
		(3 "B.Mask" user "Board Geometry/Soldermask Bottom")
		(17 "Dwgs.User" user "User.Drawings")
		(19 "Cmts.User" user "User.Comments")
		(21 "Eco1.User" user "User.Eco1")
		(23 "Eco2.User" user "User.Eco2")
		(25 "Edge.Cuts" user "Board Geometry/Outline")
		(27 "Margin" user)
		(31 "F.CrtYd" user "Package Geometry/Place Bound Top")
		(29 "B.CrtYd" user "Package Geometry/Place Bound Bottom")
		(35 "F.Fab" user "Ref Des/Assembly Top")
		(33 "B.Fab" user "Ref Des/Assembly Bottom")
	)
	(footprint ""
		(layer "F.Cu")
		(at 105.312464 -238.162592 90)
		(property "Reference" "C310"
			(at 0 0 90)
			(layer "F.SilkS")
			(hide yes)
			(effects
				(font
					(size 1.27 1.27)
				)
			)
		)
		(property "Value" ""
			(at 0 0 90)
			(layer "F.Fab")
			(effects
				(font
					(size 1.27 1.27)
				)
			)
		)
		(duplicate_pad_numbers_are_jumpers no)
		(fp_line
			(start 0.7874 -0.4064)
			(end 0.7874 0.4064)
			(stroke
				(width 0.1524)
				(type default)
			)
			(layer "F.SilkS")
		)
		(fp_line
			(start -0.7874 -0.4064)
			(end 0.7874 -0.4064)
			(stroke
				(width 0.1524)
				(type default)
			)
			(layer "F.SilkS")
		)
		(fp_line
			(start 0.7874 0.4064)
			(end -0.7874 0.4064)
			(stroke
				(width 0.1524)
				(type default)
			)
			(layer "F.SilkS")
		)
		(fp_line
			(start -0.7874 0.4064)
			(end -0.7874 -0.4064)
			(stroke
				(width 0.1524)
				(type default)
			)
			(layer "F.SilkS")
		)
		(fp_line
			(start -0.12065 -0.305054)
			(end -0.12065 -0.2794)
			(stroke
				(width 0.1)
				(type default)
			)
			(layer "F.Fab")
		)
		(fp_line
			(start -0.67945 -0.305054)
			(end -0.12065 -0.305054)
			(stroke
				(width 0.1)
				(type default)
			)
			(layer "F.Fab")
		)
		(fp_line
			(start 0.67945 -0.3048)
			(end 0.67945 0.3048)
			(stroke
				(width 0.1)
				(type default)
			)
			(layer "F.Fab")
		)
		(fp_line
			(start 0.12065 -0.3048)
			(end 0.67945 -0.3048)
			(stroke
				(width 0.1)
				(type default)
			)
			(layer "F.Fab")
		)
		(fp_line
			(start 0.12065 -0.2794)
			(end 0.12065 -0.3048)
			(stroke
				(width 0.1)
				(type default)
			)
			(layer "F.Fab")
		)
		(fp_line
			(start -0.12065 -0.2794)
			(end 0.12065 -0.2794)
			(stroke
				(width 0.1)
				(type default)
			)
			(layer "F.Fab")
		)
		(fp_line
			(start 0.120396 0.2794)
			(end -0.12065 0.2794)
			(stroke
				(width 0.1)
				(type default)
			)
			(layer "F.Fab")
		)
		(fp_line
			(start -0.12065 0.2794)
			(end -0.12065 0.3048)
			(stroke
				(width 0.1)
				(type default)
			)
			(layer "F.Fab")
		)
		(fp_line
			(start 0.67945 0.3048)
			(end 0.120396 0.3048)
			(stroke
				(width 0.1)
				(type default)
			)
			(layer "F.Fab")
		)
		(fp_line
			(start 0.120396 0.3048)
			(end 0.120396 0.2794)
			(stroke
				(width 0.1)
				(type default)
			)
			(layer "F.Fab")
		)
		(fp_line
			(start -0.12065 0.3048)
			(end -0.67945 0.3048)
			(stroke
				(width 0.1)
				(type default)
			)
			(layer "F.Fab")
		)
		(fp_line
			(start -0.67945 0.3048)
			(end -0.67945 -0.305054)
			(stroke
				(width 0.1)
				(type default)
			)
			(layer "F.Fab")
		)
		(pad "1" smd circle
			(at -0.40005 0 90)
			(size 0 0)
			(layers "F.Cu" "F.Mask" "F.Paste")
			(net "PVNN_MAIN_CPU1")
		)
		(pad "2" smd circle
			(at 0.40005 0 90)
			(size 0 0)
			(layers "F.Cu" "F.Mask" "F.Paste")
			(net "GND")
		)
	)
)
